(kicad_pcb
	(version 20260206)
	(generator "pcbnew")
	(generator_version "10.0")
	(general
		(thickness 1.6)
		(legacy_teardrops no)
	)
	(paper "A4")
	(title_block
		(title "v1-chassis-manager — T6M_CM_d_v01_1031_1645.brd")
		(comment 1 "Open CloudServer (Microsoft) / footprints 1356-1364 of 2512")
	)
	(layers
		(0 "F.Cu" signal "TOP")
		(4 "In1.Cu" signal "GND1")
		(6 "In2.Cu" signal "IN1")
		(8 "In3.Cu" signal "VCC1")
		(10 "In4.Cu" signal "VCC2")
		(12 "In5.Cu" signal "GND2")
		(14 "In6.Cu" signal "IN2")
		(16 "In7.Cu" signal "IN3")
		(18 "In8.Cu" signal "GND3")
		(2 "B.Cu" signal "BOTTOM")
		(9 "F.Adhes" user "F.Adhesive")
		(11 "B.Adhes" user "B.Adhesive")
		(13 "F.Paste" user "Package Geometry/Pastemask Top")
		(15 "B.Paste" user "Package Geometry/Pastemask Bottom")
		(5 "F.SilkS" user "Ref Des/Silkscreen Top")
		(7 "B.SilkS" user "Ref Des/Silkscreen Bottom")
		(1 "F.Mask" user "Board Geometry/Soldermask Top")
		(3 "B.Mask" user "Board Geometry/Soldermask Bottom")
		(17 "Dwgs.User" user "User.Drawings")
		(19 "Cmts.User" user "User.Comments")
		(21 "Eco1.User" user "User.Eco1")
		(23 "Eco2.User" user "User.Eco2")
		(25 "Edge.Cuts" user "Board Geometry/Outline")
		(27 "Margin" user)
		(31 "F.CrtYd" user "Package Geometry/Place Bound Top")
		(29 "B.CrtYd" user "Package Geometry/Place Bound Bottom")
		(35 "F.Fab" user "Ref Des/Assembly Top")
		(33 "B.Fab" user "Ref Des/Assembly Bottom")
	)
	(footprint ""
		(layer "F.Cu")
		(at 126.90729 -167.685212)
		(property "Reference" "C902"
			(at -1.617218 -4.22402 0)
			(unlocked yes)
			(layer "F.SilkS")
			(effects
				(font
					(size 0.7874 0.5842)
					(thickness 0.1524)
				)
				(justify left)
			)
		)
		(property "Value" ""
			(at 0 0 0)
			(layer "F.Fab")
			(effects
				(font
					(size 1.27 1.27)
				)
			)
		)
		(duplicate_pad_numbers_are_jumpers no)
		(fp_line
			(start -0.7874 -0.4064)
			(end 0.7874 -0.4064)
			(stroke
				(width 0.1524)
				(type default)
			)
			(layer "F.SilkS")
		)
		(fp_line
			(start -0.7874 0.4064)
			(end -0.7874 -0.4064)
			(stroke
				(width 0.1524)
				(type default)
			)
			(layer "F.SilkS")
		)
		(fp_line
			(start 0 0.381)
			(end 0 -0.381)
			(stroke
				(width 0.1524)
				(type default)
			)
			(layer "F.SilkS")
		)
		(fp_line
			(start 0.7874 -0.4064)
			(end 0.7874 0.4064)
			(stroke
				(width 0.1524)
				(type default)
			)
			(layer "F.SilkS")
		)
		(fp_line
			(start 0.7874 0.4064)
			(end -0.7874 0.4064)
			(stroke
				(width 0.1524)
				(type default)
			)
			(layer "F.SilkS")
		)
		(fp_poly
			(pts
				(xy -0.5334 0.254) (xy -0.635 0.254) (xy -0.635 0.2286) (xy -0.635 -0.254) (xy -0.5334 -0.254) (xy -0.5334 -0.2794)
				(xy 0.5334 -0.2794) (xy 0.5334 -0.254) (xy 0.635 -0.254) (xy 0.635 0.254) (xy 0.5334 0.254) (xy 0.5334 0.2794)
				(xy -0.508 0.2794) (xy -0.5334 0.2794)
			)
			(stroke
				(width 0)
				(type default)
			)
			(fill no)
			(layer "F.CrtYd")
		)
		(pad "1" smd rect
			(at 0.40005 0)
			(size 0.4572 0.508)
			(layers "F.Cu" "F.Mask" "F.Paste")
			(net "P3V3_NODE1")
		)
		(pad "2" smd rect
			(at -0.40005 0)
			(size 0.4572 0.508)
			(layers "F.Cu" "F.Mask" "F.Paste")
			(net "GND")
		)
	)
	(footprint ""
		(layer "F.Cu")
		(at 179.000404 -135.991346)
		(property "Reference" "R1043"
			(at 4.535678 0.127762 0)
			(unlocked yes)
			(layer "F.SilkS")
			(effects
				(font
					(size 0.7874 0.5842)
					(thickness 0.1524)
				)
				(justify left)
			)
		)
		(property "Value" ""
			(at 0 0 0)
			(layer "F.Fab")
			(effects
				(font
					(size 1.27 1.27)
				)
			)
		)
		(duplicate_pad_numbers_are_jumpers no)
		(fp_line
			(start -0.7874 -0.4064)
			(end 0.7874 -0.4064)
			(stroke
				(width 0.1524)
				(type default)
			)
			(layer "F.SilkS")
		)
		(fp_line
			(start -0.7874 0.4064)
			(end -0.7874 -0.4064)
			(stroke
				(width 0.1524)
				(type default)
			)
			(layer "F.SilkS")
		)
		(fp_line
			(start 0.7874 -0.4064)
			(end 0.7874 0.4064)
			(stroke
				(width 0.1524)
				(type default)
			)
			(layer "F.SilkS")
		)
		(fp_line
			(start 0.7874 0.4064)
			(end -0.7874 0.4064)
			(stroke
				(width 0.1524)
				(type default)
			)
			(layer "F.SilkS")
		)
		(fp_poly
			(pts
				(xy -0.508 0.2794) (xy -0.508 0.2286) (xy -0.635 0.2286) (xy -0.635 -0.254) (xy -0.5334 -0.254)
				(xy -0.5334 -0.2794) (xy 0.5334 -0.2794) (xy 0.5334 -0.254) (xy 0.635 -0.254) (xy 0.635 0.254) (xy 0.5334 0.254)
				(xy 0.5334 0.2794)
			)
			(stroke
				(width 0)
				(type default)
			)
			(fill no)
			(layer "F.CrtYd")
		)
		(pad "1" smd rect
			(at 0.40005 0)
			(size 0.4572 0.508)
			(layers "F.Cu" "F.Mask" "F.Paste")
			(net "FM_CPLD_NODE1_WDT_R")
		)
		(pad "2" smd rect
			(at -0.40005 0)
			(size 0.4572 0.508)
			(layers "F.Cu" "F.Mask" "F.Paste")
			(net "P1V05_NODE1")
		)
	)
	(footprint ""
		(layer "F.Cu")
		(at 42.662602 -163.558982)
		(property "Reference" "C399"
			(at -1.90119 1.071118 0)
			(unlocked yes)
			(layer "F.SilkS")
			(effects
				(font
					(size 0.7874 0.5842)
					(thickness 0.1524)
				)
				(justify left)
			)
		)
		(property "Value" ""
			(at 0 0 0)
			(layer "F.Fab")
			(effects
				(font
					(size 1.27 1.27)
				)
			)
		)
		(duplicate_pad_numbers_are_jumpers no)
		(fp_line
			(start -0.7874 -0.4064)
			(end 0.7874 -0.4064)
			(stroke
				(width 0.1524)
				(type default)
			)
			(layer "F.SilkS")
		)
		(fp_line
			(start -0.7874 0.4064)
			(end -0.7874 -0.4064)
			(stroke
				(width 0.1524)
				(type default)
			)
			(layer "F.SilkS")
		)
		(fp_line
			(start 0 0.381)
			(end 0 -0.381)
			(stroke
				(width 0.1524)
				(type default)
			)
			(layer "F.SilkS")
		)
		(fp_line
			(start 0.7874 -0.4064)
			(end 0.7874 0.4064)
			(stroke
				(width 0.1524)
				(type default)
			)
			(layer "F.SilkS")
		)
		(fp_line
			(start 0.7874 0.4064)
			(end -0.7874 0.4064)
			(stroke
				(width 0.1524)
				(type default)
			)
			(layer "F.SilkS")
		)
		(fp_poly
			(pts
				(xy -0.5334 0.254) (xy -0.635 0.254) (xy -0.635 0.2286) (xy -0.635 -0.254) (xy -0.5334 -0.254) (xy -0.5334 -0.2794)
				(xy 0.5334 -0.2794) (xy 0.5334 -0.254) (xy 0.635 -0.254) (xy 0.635 0.254) (xy 0.5334 0.254) (xy 0.5334 0.2794)
				(xy -0.508 0.2794) (xy -0.5334 0.2794)
			)
			(stroke
				(width 0)
				(type default)
			)
			(fill no)
			(layer "F.CrtYd")
		)
		(pad "1" smd rect
			(at 0.40005 0)
			(size 0.4572 0.508)
			(layers "F.Cu" "F.Mask" "F.Paste")
			(net "LAN1_XTAL_IN")
		)
		(pad "2" smd rect
			(at -0.40005 0)
			(size 0.4572 0.508)
			(layers "F.Cu" "F.Mask" "F.Paste")
			(net "GND")
		)
	)
	(footprint ""
		(layer "F.Cu")
		(at 166.73322 -119.39651)
		(property "Reference" "R1030"
			(at -2.81559 8.725408 0)
			(unlocked yes)
			(layer "F.SilkS")
			(effects
				(font
					(size 0.7874 0.5842)
					(thickness 0.1524)
				)
				(justify left)
			)
		)
		(property "Value" ""
			(at 0 0 0)
			(layer "F.Fab")
			(effects
				(font
					(size 1.27 1.27)
				)
			)
		)
		(duplicate_pad_numbers_are_jumpers no)
		(fp_line
			(start -0.7874 -0.4064)
			(end 0.7874 -0.4064)
			(stroke
				(width 0.1524)
				(type default)
			)
			(layer "F.SilkS")
		)
		(fp_line
			(start -0.7874 0.4064)
			(end -0.7874 -0.4064)
			(stroke
				(width 0.1524)
				(type default)
			)
			(layer "F.SilkS")
		)
		(fp_line
			(start 0.7874 -0.4064)
			(end 0.7874 0.4064)
			(stroke
				(width 0.1524)
				(type default)
			)
			(layer "F.SilkS")
		)
		(fp_line
			(start 0.7874 0.4064)
			(end -0.7874 0.4064)
			(stroke
				(width 0.1524)
				(type default)
			)
			(layer "F.SilkS")
		)
		(fp_poly
			(pts
				(xy -0.508 0.2794) (xy -0.508 0.2286) (xy -0.635 0.2286) (xy -0.635 -0.254) (xy -0.5334 -0.254)
				(xy -0.5334 -0.2794) (xy 0.5334 -0.2794) (xy 0.5334 -0.254) (xy 0.635 -0.254) (xy 0.635 0.254) (xy 0.5334 0.254)
				(xy 0.5334 0.2794)
			)
			(stroke
				(width 0)
				(type default)
			)
			(fill no)
			(layer "F.CrtYd")
		)
		(pad "1" smd rect
			(at 0.40005 0)
			(size 0.4572 0.508)
			(layers "F.Cu" "F.Mask" "F.Paste")
			(net "FM_CPLD_NODE1_BMC_SRST_L")
		)
		(pad "2" smd rect
			(at -0.40005 0)
			(size 0.4572 0.508)
			(layers "F.Cu" "F.Mask" "F.Paste")
			(net "FM_BMC_NODE1_RESET_L")
		)
	)
	(footprint ""
		(layer "F.Cu")
		(at 130.60807 -110.92815 180)
		(property "Reference" "C12"
			(at 5.280406 0.023368 0)
			(unlocked yes)
			(layer "F.SilkS")
			(effects
				(font
					(size 0.7874 0.5842)
					(thickness 0.1524)
				)
				(justify left)
			)
		)
		(property "Value" ""
			(at 0 0 180)
			(layer "F.Fab")
			(effects
				(font
					(size 1.27 1.27)
				)
			)
		)
		(duplicate_pad_numbers_are_jumpers no)
		(fp_line
			(start 0.7874 0.4064)
			(end -0.7874 0.4064)
			(stroke
				(width 0.1524)
				(type default)
			)
			(layer "F.SilkS")
		)
		(fp_line
			(start 0.7874 -0.4064)
			(end 0.7874 0.4064)
			(stroke
				(width 0.1524)
				(type default)
			)
			(layer "F.SilkS")
		)
		(fp_line
			(start 0 0.381)
			(end 0 -0.381)
			(stroke
				(width 0.1524)
				(type default)
			)
			(layer "F.SilkS")
		)
		(fp_line
			(start -0.7874 0.4064)
			(end -0.7874 -0.4064)
			(stroke
				(width 0.1524)
				(type default)
			)
			(layer "F.SilkS")
		)
		(fp_line
			(start -0.7874 -0.4064)
			(end 0.7874 -0.4064)
			(stroke
				(width 0.1524)
				(type default)
			)
			(layer "F.SilkS")
		)
		(fp_poly
			(pts
				(xy -0.5334 0.254) (xy -0.635 0.254) (xy -0.635 0.2286) (xy -0.635 -0.254) (xy -0.5334 -0.254) (xy -0.5334 -0.2794)
				(xy 0.5334 -0.2794) (xy 0.5334 -0.254) (xy 0.635 -0.254) (xy 0.635 0.254) (xy 0.5334 0.254) (xy 0.5334 0.2794)
				(xy -0.508 0.2794) (xy -0.5334 0.2794)
			)
			(stroke
				(width 0)
				(type default)
			)
			(fill no)
			(layer "F.CrtYd")
		)
		(pad "1" smd rect
			(at 0.40005 0 180)
			(size 0.4572 0.508)
			(layers "F.Cu" "F.Mask" "F.Paste")
			(net "XTAL_CLK_NODE1_X1")
		)
		(pad "2" smd rect
			(at -0.40005 0 180)
			(size 0.4572 0.508)
			(layers "F.Cu" "F.Mask" "F.Paste")
			(net "GND")
		)
	)
	(footprint ""
		(layer "F.Cu")
		(at 59.957208 -148.241258)
		(property "Reference" "C262"
			(at -29.678122 -7.053834 0)
			(unlocked yes)
			(layer "F.SilkS")
			(effects
				(font
					(size 0.7874 0.5842)
					(thickness 0.1524)
				)
			)
		)
		(property "Value" ""
			(at 0 0 0)
			(layer "F.Fab")
			(effects
				(font
					(size 1.27 1.27)
				)
			)
		)
		(duplicate_pad_numbers_are_jumpers no)
		(fp_line
			(start -1.2954 -0.5842)
			(end 1.2954 -0.5842)
			(stroke
				(width 0.1524)
				(type default)
			)
			(layer "F.SilkS")
		)
		(fp_line
			(start -1.2954 0.5842)
			(end -1.2954 -0.5842)
			(stroke
				(width 0.1524)
				(type default)
			)
			(layer "F.SilkS")
		)
		(fp_line
			(start 0 -0.5842)
			(end 0 0.5842)
			(stroke
				(width 0.1524)
				(type default)
			)
			(layer "F.SilkS")
		)
		(fp_line
			(start 1.2954 -0.5842)
			(end 1.2954 0.5842)
			(stroke
				(width 0.1524)
				(type default)
			)
			(layer "F.SilkS")
		)
		(fp_line
			(start 1.2954 0.5842)
			(end -1.2954 0.5842)
			(stroke
				(width 0.1524)
				(type default)
			)
			(layer "F.SilkS")
		)
		(fp_poly
			(pts
				(xy 0.8636 -0.4572) (xy 0.8636 -0.3556) (xy 1.143 -0.3556) (xy 1.143 0.3556) (xy 0.8636 0.3556)
				(xy 0.8636 0.4572) (xy -0.8636 0.4572) (xy -0.8636 0.3556) (xy -1.143 0.3556) (xy -1.143 -0.3556)
				(xy -0.8636 -0.3556) (xy -0.8636 -0.4572)
			)
			(stroke
				(width 0)
				(type default)
			)
			(fill no)
			(layer "F.CrtYd")
		)
		(fp_line
			(start -0.884936 -0.504952)
			(end 0.884936 -0.504952)
			(stroke
				(width 0.1)
				(type default)
			)
			(layer "F.Fab")
		)
		(fp_line
			(start -0.884936 0.504952)
			(end -0.884936 -0.504952)
			(stroke
				(width 0.1)
				(type default)
			)
			(layer "F.Fab")
		)
		(fp_line
			(start 0.884936 -0.504952)
			(end 0.884936 0.504952)
			(stroke
				(width 0.1)
				(type default)
			)
			(layer "F.Fab")
		)
		(fp_line
			(start 0.884936 0.504952)
			(end -0.884936 0.504952)
			(stroke
				(width 0.1)
				(type default)
			)
			(layer "F.Fab")
		)
		(pad "1" smd rect
			(at 0.7366 0 90)
			(size 0.7112 0.8128)
			(layers "F.Cu" "F.Mask" "F.Paste")
			(net "BMC_NODE1_DACAV33")
		)
		(pad "2" smd rect
			(at -0.7366 0 90)
			(size 0.7112 0.8128)
			(layers "F.Cu" "F.Mask" "F.Paste")
			(net "GND")
		)
	)
	(footprint ""
		(layer "F.Cu")
		(at 131.81076 -185.053224 90)
		(property "Reference" "C755"
			(at 4.663186 -0.954278 90)
			(unlocked yes)
			(layer "F.SilkS")
			(effects
				(font
					(size 0.7874 0.5842)
					(thickness 0.1524)
				)
				(justify left)
			)
		)
		(property "Value" ""
			(at 0 0 90)
			(layer "F.Fab")
			(effects
				(font
					(size 1.27 1.27)
				)
			)
		)
		(duplicate_pad_numbers_are_jumpers no)
		(fp_line
			(start 0.7874 -0.4064)
			(end 0.7874 0.4064)
			(stroke
				(width 0.1524)
				(type default)
			)
			(layer "F.SilkS")
		)
		(fp_line
			(start -0.7874 -0.4064)
			(end 0.7874 -0.4064)
			(stroke
				(width 0.1524)
				(type default)
			)
			(layer "F.SilkS")
		)
		(fp_line
			(start 0 0.381)
			(end 0 -0.381)
			(stroke
				(width 0.1524)
				(type default)
			)
			(layer "F.SilkS")
		)
		(fp_line
			(start 0.7874 0.4064)
			(end -0.7874 0.4064)
			(stroke
				(width 0.1524)
				(type default)
			)
			(layer "F.SilkS")
		)
		(fp_line
			(start -0.7874 0.4064)
			(end -0.7874 -0.4064)
			(stroke
				(width 0.1524)
				(type default)
			)
			(layer "F.SilkS")
		)
		(fp_poly
			(pts
				(xy -0.5334 0.254) (xy -0.635 0.254) (xy -0.635 0.2286) (xy -0.635 -0.254) (xy -0.5334 -0.254) (xy -0.5334 -0.2794)
				(xy 0.5334 -0.2794) (xy 0.5334 -0.254) (xy 0.635 -0.254) (xy 0.635 0.254) (xy 0.5334 0.254) (xy 0.5334 0.2794)
				(xy -0.508 0.2794) (xy -0.5334 0.2794)
			)
			(stroke
				(width 0)
				(type default)
			)
			(fill no)
			(layer "F.CrtYd")
		)
		(pad "1" smd rect
			(at 0.40005 0 90)
			(size 0.4572 0.508)
			(layers "F.Cu" "F.Mask" "F.Paste")
			(net "UART_T10_NODE3_RXD")
		)
		(pad "2" smd rect
			(at -0.40005 0 90)
			(size 0.4572 0.508)
			(layers "F.Cu" "F.Mask" "F.Paste")
			(net "GND")
		)
	)
	(footprint ""
		(layer "F.Cu")
		(at 141.08176 -188.126624 90)
		(property "Reference" "C636"
			(at 5.519674 -0.479552 90)
			(unlocked yes)
			(layer "F.SilkS")
			(effects
				(font
					(size 0.7874 0.5842)
					(thickness 0.1524)
				)
				(justify left)
			)
		)
		(property "Value" ""
			(at 0 0 90)
			(layer "F.Fab")
			(effects
				(font
					(size 1.27 1.27)
				)
			)
		)
		(duplicate_pad_numbers_are_jumpers no)
		(fp_line
			(start 0.7874 -0.4064)
			(end 0.7874 0.4064)
			(stroke
				(width 0.1524)
				(type default)
			)
			(layer "F.SilkS")
		)
		(fp_line
			(start -0.7874 -0.4064)
			(end 0.7874 -0.4064)
			(stroke
				(width 0.1524)
				(type default)
			)
			(layer "F.SilkS")
		)
		(fp_line
			(start 0 0.381)
			(end 0 -0.381)
			(stroke
				(width 0.1524)
				(type default)
			)
			(layer "F.SilkS")
		)
		(fp_line
			(start 0.7874 0.4064)
			(end -0.7874 0.4064)
			(stroke
				(width 0.1524)
				(type default)
			)
			(layer "F.SilkS")
		)
		(fp_line
			(start -0.7874 0.4064)
			(end -0.7874 -0.4064)
			(stroke
				(width 0.1524)
				(type default)
			)
			(layer "F.SilkS")
		)
		(fp_poly
			(pts
				(xy -0.5334 0.254) (xy -0.635 0.254) (xy -0.635 0.2286) (xy -0.635 -0.254) (xy -0.5334 -0.254) (xy -0.5334 -0.2794)
				(xy 0.5334 -0.2794) (xy 0.5334 -0.254) (xy 0.635 -0.254) (xy 0.635 0.254) (xy 0.5334 0.254) (xy 0.5334 0.2794)
				(xy -0.508 0.2794) (xy -0.5334 0.2794)
			)
			(stroke
				(width 0)
				(type default)
			)
			(fill no)
			(layer "F.CrtYd")
		)
		(pad "1" smd rect
			(at 0.40005 0 90)
			(size 0.4572 0.508)
			(layers "F.Cu" "F.Mask" "F.Paste")
			(net "T10_NODE1_EN_R")
		)
		(pad "2" smd rect
			(at -0.40005 0 90)
			(size 0.4572 0.508)
			(layers "F.Cu" "F.Mask" "F.Paste")
			(net "GND")
		)
	)
	(footprint ""
		(layer "F.Cu")
		(at 174.676562 -138.00455 90)
		(property "Reference" "U106"
			(at 2.306574 -0.515366 0)
			(unlocked yes)
			(layer "F.SilkS")
			(effects
				(font
					(size 0.7874 0.5842)
					(thickness 0.1524)
				)
				(justify left)
			)
		)
		(property "Value" ""
			(at 0 0 90)
			(layer "F.Fab")
			(effects
				(font
					(size 1.27 1.27)
				)
			)
		)
		(duplicate_pad_numbers_are_jumpers no)
		(fp_line
			(start 1.549908 -2.032)
			(end 1.549908 2.032)
			(stroke
				(width 0.1524)
				(type default)
			)
			(layer "F.SilkS")
		)
		(fp_line
			(start -1.549908 -2.032)
			(end 1.549908 -2.032)
			(stroke
				(width 0.1524)
				(type default)
			)
			(layer "F.SilkS")
		)
		(fp_line
			(start 1.549908 2.032)
			(end -1.549908 2.032)
			(stroke
				(width 0.1524)
				(type default)
			)
			(layer "F.SilkS")
		)
		(fp_line
			(start -1.549908 2.032)
			(end -1.549908 -2.032)
			(stroke
				(width 0.1524)
				(type default)
			)
			(layer "F.SilkS")
		)
		(fp_poly
			(pts
				(xy -2.9464 1.016) (xy -2.9464 1.524) (xy -2.1844 1.27)
			)
			(stroke
				(width 0)
				(type default)
			)
			(fill yes)
			(layer "F.SilkS")
		)
		(fp_poly
			(pts
				(xy -1.549908 0.849884) (xy -1.2319 0.849884) (xy -1.2319 1.9431) (xy -1.1811 1.9431) (xy 1.1811 1.9431)
				(xy 1.2319 1.9431) (xy 1.2319 0.849884) (xy 1.549908 0.849884) (xy 1.549908 -0.849884) (xy 1.2319 -0.849884)
				(xy 1.2319 -1.9431) (xy 1.1811 -1.9431) (xy -1.1811 -1.9431) (xy -1.2319 -1.9431) (xy -1.2319 -0.849884)
				(xy -1.549908 -0.849884)
			)
			(stroke
				(width 0)
				(type default)
			)
			(fill no)
			(layer "F.CrtYd")
		)
		(fp_line
			(start 1.549908 -0.849884)
			(end -1.549908 -0.849884)
			(stroke
				(width 0.1)
				(type default)
			)
			(layer "F.Fab")
		)
		(fp_line
			(start -1.549908 -0.849884)
			(end -1.549908 0.849884)
			(stroke
				(width 0.1)
				(type default)
			)
			(layer "F.Fab")
		)
		(fp_line
			(start 1.549908 0.849884)
			(end 1.549908 -0.849884)
			(stroke
				(width 0.1)
				(type default)
			)
			(layer "F.Fab")
		)
		(fp_line
			(start -1.549908 0.849884)
			(end 1.549908 0.849884)
			(stroke
				(width 0.1)
				(type default)
			)
			(layer "F.Fab")
		)
		(fp_text user "4"
			(at 2.184908 -1.922272 0)
			(unlocked yes)
			(layer "F.SilkS")
			(effects
				(font
					(size 0.635 0.4064)
					(thickness 0.1524)
				)
				(justify left)
			)
		)
		(fp_text user "5"
			(at -2.2352 -1.04775 90)
			(unlocked yes)
			(layer "F.SilkS")
			(effects
				(font
					(size 0.635 0.4064)
					(thickness 0.1524)
				)
				(justify left)
			)
		)
		(fp_text user "1"
			(at -2.0955 1.373632 90)
			(unlocked yes)
			(layer "F.SilkS")
			(effects
				(font
					(size 0.635 0.4064)
					(thickness 0.1524)
				)
				(justify left)
			)
		)
		(fp_text user "3"
			(at 1.232916 2.408428 0)
			(unlocked yes)
			(layer "F.SilkS")
			(effects
				(font
					(size 0.635 0.4064)
					(thickness 0.1524)
				)
				(justify left)
			)
		)
		(pad "1" smd rect
			(at -0.94996 1.225042 90)
			(size 0.4572 1.3208)
			(layers "F.Cu" "F.Mask" "F.Paste")
			(net "Net_1703")
		)
		(pad "2" smd rect
			(at 0 1.225042 90)
			(size 0.4572 1.3208)
			(layers "F.Cu" "F.Mask" "F.Paste")
			(net "PWR_BTN_NODE1_C_L")
		)
		(pad "3" smd rect
			(at 0.94996 1.225042 90)
			(size 0.4572 1.3208)
			(layers "F.Cu" "F.Mask" "F.Paste")
			(net "GND")
		)
		(pad "4" smd rect
			(at 0.94996 -1.225042 90)
			(size 0.4572 1.3208)
			(layers "F.Cu" "F.Mask" "F.Paste")
			(net "FM_CPLD_NODE1_PWR_BTN_L")
		)
		(pad "5" smd rect
			(at -0.94996 -1.225042 90)
			(size 0.4572 1.3208)
			(layers "F.Cu" "F.Mask" "F.Paste")
			(net "P3V3_STB_NODE1")
		)
	)
)
